FILE_TYPE = CONNECTIVITY;
{Allegro Design Entry HDL 17.2-2016 S081 (4005846) 1/11/2022}
"PAGE_NUMBER" = 25;
0"NC";
1"P5E_CPU0_P3_TX_DP<7:4>";
2"P5E_CPU0_P3_TX_DN<7:4>";
3"P4E_CPU0_P3_TX_DN<11:8>";
4"P4E_CPU0_P3_TX_DP<11:8>";
5"P5E_CPU0_P2_TX_DP<15:0>";
6"P5E_CPU0_P2_TX_DN<15:0>";
7"P5E_CPU0_P2_RX_DP<15:0>";
8"P5E_CPU0_P2_RX_DN<15:0>";
9"P5E_CPU0_P3_RX_DP<7:4>";
10"P5E_CPU0_P3_RX_DN<7:4>";
11"P4E_CPU0_P3_RX_DP<11:8>";
12"P4E_CPU0_P3_RX_DN<11:8>";
13"P4E_CPU0_P3_RX_DN<11>";
14"P4E_CPU0_P3_RX_DP<11>";
15"P4E_CPU0_P3_RX_DN<10>";
16"P4E_CPU0_P3_RX_DP<10>";
17"P4E_CPU0_P3_RX_DN<9>";
18"P4E_CPU0_P3_RX_DP<9>";
19"P4E_CPU0_P3_RX_DN<8>";
20"P4E_CPU0_P3_RX_DP<8>";
21"P5E_CPU0_P3_RX_DN<7>";
22"P5E_CPU0_P3_RX_DP<7>";
23"P5E_CPU0_P3_RX_DN<6>";
24"P5E_CPU0_P3_RX_DP<6>";
25"P5E_CPU0_P3_RX_DN<5>";
26"P5E_CPU0_P3_RX_DP<5>";
27"P5E_CPU0_P3_RX_DN<4>";
28"P5E_CPU0_P3_RX_DP<4>";
29"P3E_CPU0_P3_RX_DP<0>";
30"P3E_CPU0_P3_RX_DN<0>";
31"P5E_CPU0_P2_RX_DN<7>";
32"P5E_CPU0_P2_RX_DN<6>";
33"P5E_CPU0_P2_RX_DN<5>";
34"P5E_CPU0_P2_RX_DP<7>";
35"P5E_CPU0_P2_RX_DN<4>";
36"P5E_CPU0_P2_RX_DP<6>";
37"P5E_CPU0_P2_RX_DN<3>";
38"P5E_CPU0_P2_RX_DP<5>";
39"P5E_CPU0_P2_RX_DN<2>";
40"P5E_CPU0_P2_RX_DP<4>";
41"P5E_CPU0_P2_RX_DN<1>";
42"P5E_CPU0_P2_RX_DP<3>";
43"P5E_CPU0_P2_RX_DN<0>";
44"P5E_CPU0_P2_RX_DP<2>";
45"P5E_CPU0_P2_RX_DP<1>";
46"P5E_CPU0_P2_RX_DP<0>";
47"P5E_CPU0_P2_RX_DN<15>";
48"P5E_CPU0_P2_RX_DP<15>";
49"P5E_CPU0_P2_RX_DN<14>";
50"P5E_CPU0_P2_RX_DP<14>";
51"P5E_CPU0_P2_RX_DN<13>";
52"P5E_CPU0_P2_RX_DP<13>";
53"P5E_CPU0_P2_RX_DN<12>";
54"P5E_CPU0_P2_RX_DP<12>";
55"P5E_CPU0_P2_RX_DN<11>";
56"P5E_CPU0_P2_RX_DP<11>";
57"P5E_CPU0_P2_RX_DN<10>";
58"P5E_CPU0_P2_RX_DP<10>";
59"P5E_CPU0_P2_RX_DN<9>";
60"P5E_CPU0_P2_RX_DP<9>";
61"P5E_CPU0_P2_RX_DN<8>";
62"P5E_CPU0_P2_RX_DP<8>";
63"P5E_CPU0_P2_TX_DN<7>";
64"P5E_CPU0_P2_TX_DN<6>";
65"P5E_CPU0_P2_TX_DN<5>";
66"P5E_CPU0_P2_TX_DP<7>";
67"P5E_CPU0_P2_TX_DN<4>";
68"P5E_CPU0_P2_TX_DP<6>";
69"P5E_CPU0_P2_TX_DN<3>";
70"P5E_CPU0_P2_TX_DP<5>";
71"P5E_CPU0_P2_TX_DN<2>";
72"P5E_CPU0_P2_TX_DP<4>";
73"P5E_CPU0_P2_TX_DN<1>";
74"P5E_CPU0_P2_TX_DP<3>";
75"P5E_CPU0_P2_TX_DN<0>";
76"P5E_CPU0_P2_TX_DP<2>";
77"P5E_CPU0_P2_TX_DP<1>";
78"P5E_CPU0_P2_TX_DP<0>";
79"P5E_CPU0_P2_TX_DN<15>";
80"P5E_CPU0_P2_TX_DP<15>";
81"P5E_CPU0_P2_TX_DN<14>";
82"P5E_CPU0_P2_TX_DP<14>";
83"P5E_CPU0_P2_TX_DN<13>";
84"P5E_CPU0_P2_TX_DP<13>";
85"P5E_CPU0_P2_TX_DN<12>";
86"P5E_CPU0_P2_TX_DP<12>";
87"P5E_CPU0_P2_TX_DN<11>";
88"P5E_CPU0_P2_TX_DP<11>";
89"P5E_CPU0_P2_TX_DN<10>";
90"P5E_CPU0_P2_TX_DP<10>";
91"P5E_CPU0_P2_TX_DN<9>";
92"P5E_CPU0_P2_TX_DP<9>";
93"P5E_CPU0_P2_TX_DN<8>";
94"P5E_CPU0_P2_TX_DP<8>";
95"P4E_CPU0_P3_TX_DP<11>";
96"P4E_CPU0_P3_TX_DN<11>";
97"P4E_CPU0_P3_TX_DP<10>";
98"P4E_CPU0_P3_TX_DN<10>";
99"P4E_CPU0_P3_TX_DP<9>";
100"P4E_CPU0_P3_TX_DN<9>";
101"P4E_CPU0_P3_TX_DP<8>";
102"P4E_CPU0_P3_TX_DN<8>";
103"P5E_CPU0_P3_TX_DN<7>";
104"P5E_CPU0_P3_TX_DP<7>";
105"P5E_CPU0_P3_TX_DN<6>";
106"P5E_CPU0_P3_TX_DP<6>";
107"P5E_CPU0_P3_TX_DN<5>";
108"P5E_CPU0_P3_TX_DP<5>";
109"P5E_CPU0_P3_TX_DN<4>";
110"P5E_CPU0_P3_TX_DP<4>";
111"P3E_CPU0_P3_TX_DP<0>";
112"P3E_CPU0_P3_TX_DN<0>";
%"GENOA_SP5"
"17","(-5025,5075)","0","pure_quanta","I147";
;
LOCATION"U25"
$SEC"17"
CDS_SEC"17"
PART_TYPE"SMLF"
MATERIAL"IO"
VALUE"SOCKET6096_13568-001"
PART_NUMBER"DGA^6000030"
CDS_LIB"pure_quanta"
NEEDS_NO_SIZE"TRUE"
CDS_LMAN_SYM_OUTLINE"-600,950,600,-950";
"P2_RXN7"
$PN"CU30"31;
"P2_RXN6"
$PN"CN30"32;
"P2_RXN5"
$PN"CR33"33;
"P2_RXP7"
$PN"CU29"34;
"P2_TXN7"
$PN"BU29"63;
"P2_RXN4"
$PN"CU33"35;
"P2_RXP6"
$PN"CN29"36;
"P2_TXN6"
$PN"BW32"64;
"P2_RXN3"
$PN"CN33"37;
"P2_RXP5"
$PN"CR32"38;
"P2_TXN5"
$PN"CA32"65;
"P2_TXP7"
$PN"BU30"66;
"P2_RXN2"
$PN"CT36"39;
"P2_RXP4"
$PN"CU32"40;
"P2_TXN4"
$PN"BU32"67;
"P2_TXP6"
$PN"BW33"68;
"P2_RXN1"
$PN"CP36"41;
"P2_RXP3"
$PN"CN32"42;
"P2_TXN3"
$PN"BY35"69;
"P2_TXP5"
$PN"CA33"70;
"P2_RXN0"
$PN"CM36"43;
"P2_RXP2"
$PN"CT35"44;
"P2_TXN2"
$PN"CB35"71;
"P2_TXP4"
$PN"BU33"72;
"P2_RXP1"
$PN"CP35"45;
"P2_TXN1"
$PN"BV35"73;
"P2_TXP3"
$PN"BY36"74;
"P2_RXP0"
$PN"CM35"46;
"P2_TXN0"
$PN"BT35"75;
"P2_TXP2"
$PN"CB36"76;
"P2_TXP1"
$PN"BV36"77;
"P2_TXP0"
$PN"BT36"78;
"P2_TXN15"
$PN"BW23"79;
"P2_TXP15"
$PN"BW24"80;
"P2_TXN14"
$PN"CA23"81;
"P2_TXP14"
$PN"CA24"82;
"P2_TXN13"
$PN"BU23"83;
"P2_TXP13"
$PN"BU24"84;
"P2_TXN12"
$PN"BW26"85;
"P2_TXP12"
$PN"BW27"86;
"P2_TXN11"
$PN"CA26"87;
"P2_TXP11"
$PN"CA27"88;
"P2_TXN10"
$PN"BU26"89;
"P2_TXP10"
$PN"BU27"90;
"P2_TXN9"
$PN"BW29"91;
"P2_TXP9"
$PN"BW30"92;
"P2_TXN8"
$PN"CA29"93;
"P2_TXP8"
$PN"CA30"94;
"P2_RXN15"
$PN"CN24"47;
"P2_RXP15"
$PN"CN23"48;
"P2_RXN14"
$PN"CR24"49;
"P2_RXP14"
$PN"CR23"50;
"P2_RXN13"
$PN"CL24"51;
"P2_RXP13"
$PN"CL23"52;
"P2_RXN12"
$PN"CN27"53;
"P2_RXP12"
$PN"CN26"54;
"P2_RXN11"
$PN"CR27"55;
"P2_RXP11"
$PN"CR26"56;
"P2_RXN10"
$PN"CU27"57;
"P2_RXP10"
$PN"CU26"58;
"P2_RXN9"
$PN"CL27"59;
"P2_RXP9"
$PN"CL26"60;
"P2_RXN8"
$PN"CR30"61;
"P2_RXP8"
$PN"CR29"62;
%"GENOA_SP5"
"18","(-5025,2250)","0","pure_quanta","I148";
;
LOCATION"U25"
$SEC"18"
CDS_SEC"18"
PART_TYPE"SMLF"
MATERIAL"IO"
VALUE"SOCKET6096_13568-001"
PART_NUMBER"DGA^6000030"
CDS_LMAN_SYM_OUTLINE"-600,950,600,-950"
NEEDS_NO_SIZE"TRUE"
CDS_LIB"pure_quanta";
"P3_TXN15"
$PN"CE23"0;
"P3_TXP15"
$PN"CE24"0;
"P3_TXN14"
$PN"CG23"0;
"P3_TXP14"
$PN"CG24"0;
"P3_TXN13"
$PN"CC23"0;
"P3_TXP13"
$PN"CC24"0;
"P3_TXN12"
$PN"CE26"0;
"P3_TXP12"
$PN"CE27"0;
"P3_TXN11"
$PN"CG26"95;
"P3_TXP11"
$PN"CG27"96;
"P3_TXN10"
$PN"CC26"97;
"P3_TXP10"
$PN"CC27"98;
"P3_TXN9"
$PN"CE29"99;
"P3_TXP9"
$PN"CE30"100;
"P3_TXN8"
$PN"CG29"101;
"P3_TXP8"
$PN"CG30"102;
"P3_TXN7"
$PN"CC29"103;
"P3_TXP7"
$PN"CC30"104;
"P3_TXN6"
$PN"CE32"105;
"P3_TXP6"
$PN"CE33"106;
"P3_TXN5"
$PN"CG32"107;
"P3_TXP5"
$PN"CG33"108;
"P3_TXN4"
$PN"CJ32"109;
"P3_TXP4"
$PN"CJ33"110;
"P3_TXN3"
$PN"CC32"0;
"P3_TXP3"
$PN"CC33"0;
"P3_TXN2"
$PN"CH35"0;
"P3_TXP2"
$PN"CH36"0;
"P3_TXN1"
$PN"CF35"0;
"P3_TXP1"
$PN"CF36"0;
"P3_TXN0"
$PN"CD35"112;
"P3_TXP0"
$PN"CD36"111;
"P3_RXN15"
$PN"CU24"0;
"P3_RXP15"
$PN"CU23"0;
"P3_RXN14"
$PN"DA24"0;
"P3_RXP14"
$PN"DA23"0;
"P3_RXN13"
$PN"DC24"0;
"P3_RXP13"
$PN"DC23"0;
"P3_RXN12"
$PN"CW24"0;
"P3_RXP12"
$PN"CW23"0;
"P3_RXN11"
$PN"DA27"13;
"P3_RXP11"
$PN"DA26"14;
"P3_RXN10"
$PN"DC27"15;
"P3_RXP10"
$PN"DC26"16;
"P3_RXN9"
$PN"CW27"17;
"P3_RXP9"
$PN"CW26"18;
"P3_RXN8"
$PN"DA30"19;
"P3_RXP8"
$PN"DA29"20;
"P3_RXN7"
$PN"DC30"21;
"P3_RXP7"
$PN"DC29"22;
"P3_RXN6"
$PN"CW30"23;
"P3_RXP6"
$PN"CW29"24;
"P3_RXN5"
$PN"DA33"25;
"P3_RXP5"
$PN"DA32"26;
"P3_RXN4"
$PN"DC33"27;
"P3_RXP4"
$PN"DC32"28;
"P3_RXN3"
$PN"CW33"0;
"P3_RXP3"
$PN"CW32"0;
"P3_RXN2"
$PN"DB36"0;
"P3_RXP2"
$PN"DB35"0;
"P3_RXN1"
$PN"CY36"0;
"P3_RXP1"
$PN"CY35"0;
"P3_RXN0"
$PN"CV36"29;
"P3_RXP0"
$PN"CV35"30;
%"TAP"
"6","(-3700,5725)","2","mstr_standard","I151";
;
CDS_LIB"mstr_standard"
BOM_COST"IO_SLOT"
BODY_TYPE"PLUMBING"
HDL_TAP"TRUE"
ROOM"RISER1";
"B \NAC \NWC"6;
"S \NAC"
BN"1"73;
%"TAP"
"6","(-3700,5825)","2","mstr_standard","I152";
;
BOM_COST"IO_SLOT"
CDS_LIB"mstr_standard"
BODY_TYPE"PLUMBING"
HDL_TAP"TRUE"
ROOM"RISER1";
"B \NAC \NWC"6;
"S \NAC"
BN"0"75;
%"TAP"
"6","(-3850,5875)","2","mstr_standard","I153";
;
CDS_LIB"mstr_standard"
BOM_COST"IO_SLOT"
BODY_TYPE"PLUMBING"
HDL_TAP"TRUE"
ROOM"RISER1";
"B \NAC \NWC"5;
"S \NAC"
BN"0"78;
%"TAP"
"6","(-3850,5775)","2","mstr_standard","I154";
;
CDS_LIB"mstr_standard"
BOM_COST"IO_SLOT"
BODY_TYPE"PLUMBING"
HDL_TAP"TRUE"
ROOM"RISER1";
"B \NAC \NWC"5;
"S \NAC"
BN"1"77;
%"TAP"
"6","(-3700,5625)","2","standard","I155";
;
CDS_LIB"standard"
BOM_COST"IO_SLOT"
BODY_TYPE"PLUMBING"
HDL_TAP"TRUE"
ROOM"RISER1";
"B \NAC \NWC"6;
"S \NAC"
BN"2"71;
%"TAP"
"6","(-3700,5525)","2","standard","I156";
;
CDS_LIB"standard"
BOM_COST"IO_SLOT"
BODY_TYPE"PLUMBING"
HDL_TAP"TRUE"
ROOM"RISER1";
"B \NAC \NWC"6;
"S \NAC"
BN"3"69;
%"TAP"
"6","(-3850,5675)","2","standard","I157";
;
CDS_LIB"standard"
BOM_COST"IO_SLOT"
BODY_TYPE"PLUMBING"
HDL_TAP"TRUE"
ROOM"RISER1";
"B \NAC \NWC"5;
"S \NAC"
BN"2"76;
%"TAP"
"6","(-3850,5575)","2","standard","I158";
;
CDS_LIB"standard"
BOM_COST"IO_SLOT"
BODY_TYPE"PLUMBING"
HDL_TAP"TRUE"
ROOM"RISER1";
"B \NAC \NWC"5;
"S \NAC"
BN"3"74;
%"TAP"
"6","(-3850,5475)","2","standard","I159";
;
CDS_LIB"standard"
BOM_COST"IO_SLOT"
BODY_TYPE"PLUMBING"
HDL_TAP"TRUE"
ROOM"RISER1";
"B \NAC \NWC"5;
"S \NAC"
BN"4"72;
%"TAP"
"6","(-3700,5325)","2","standard","I160";
;
CDS_LIB"standard"
BOM_COST"IO_SLOT"
BODY_TYPE"PLUMBING"
HDL_TAP"TRUE"
ROOM"RISER1";
"B \NAC \NWC"6;
"S \NAC"
BN"5"65;
%"TAP"
"6","(-3700,5425)","2","standard","I161";
;
CDS_LIB"standard"
BOM_COST"IO_SLOT"
BODY_TYPE"PLUMBING"
HDL_TAP"TRUE"
ROOM"RISER1";
"B \NAC \NWC"6;
"S \NAC"
BN"4"67;
%"TAP"
"6","(-3700,5225)","2","standard","I162";
;
CDS_LIB"standard"
BOM_COST"IO_SLOT"
BODY_TYPE"PLUMBING"
HDL_TAP"TRUE"
ROOM"RISER1";
"B \NAC \NWC"6;
"S \NAC"
BN"6"64;
%"TAP"
"6","(-3850,5375)","2","standard","I163";
;
CDS_LIB"standard"
BOM_COST"IO_SLOT"
BODY_TYPE"PLUMBING"
HDL_TAP"TRUE"
ROOM"RISER1";
"B \NAC \NWC"5;
"S \NAC"
BN"5"70;
%"TAP"
"6","(-3850,5275)","2","standard","I164";
;
CDS_LIB"standard"
BOM_COST"IO_SLOT"
BODY_TYPE"PLUMBING"
HDL_TAP"TRUE"
ROOM"RISER1";
"B \NAC \NWC"5;
"S \NAC"
BN"6"68;
%"TAP"
"6","(-3700,5125)","2","standard","I165";
;
CDS_LIB"standard"
BOM_COST"IO_SLOT"
BODY_TYPE"PLUMBING"
HDL_TAP"TRUE"
ROOM"RISER1";
"B \NAC \NWC"6;
"S \NAC"
BN"7"63;
%"TAP"
"6","(-3700,5025)","2","standard","I166";
;
CDS_LIB"standard"
BOM_COST"IO_SLOT"
BODY_TYPE"PLUMBING"
HDL_TAP"TRUE"
ROOM"RISER1";
"B \NAC \NWC"6;
"S \NAC"
BN"8"93;
%"TAP"
"6","(-3850,5175)","2","standard","I167";
;
CDS_LIB"standard"
BOM_COST"IO_SLOT"
BODY_TYPE"PLUMBING"
HDL_TAP"TRUE"
ROOM"RISER1";
"B \NAC \NWC"5;
"S \NAC"
BN"7"66;
%"TAP"
"6","(-3850,5075)","2","standard","I168";
;
CDS_LIB"standard"
BOM_COST"IO_SLOT"
BODY_TYPE"PLUMBING"
HDL_TAP"TRUE"
ROOM"RISER1";
"B \NAC \NWC"5;
"S \NAC"
BN"8"94;
%"TAP"
"6","(-3850,4975)","2","standard","I169";
;
CDS_LIB"standard"
BOM_COST"IO_SLOT"
BODY_TYPE"PLUMBING"
HDL_TAP"TRUE"
ROOM"RISER1";
"B \NAC \NWC"5;
"S \NAC"
BN"9"92;
%"TAP"
"6","(-3700,4825)","2","standard","I170";
;
CDS_LIB"standard"
BOM_COST"IO_SLOT"
BODY_TYPE"PLUMBING"
HDL_TAP"TRUE"
ROOM"RISER1";
"B \NAC \NWC"6;
"S \NAC"
BN"10"89;
%"TAP"
"6","(-3700,4925)","2","standard","I171";
;
CDS_LIB"standard"
BOM_COST"IO_SLOT"
BODY_TYPE"PLUMBING"
HDL_TAP"TRUE"
ROOM"RISER1";
"B \NAC \NWC"6;
"S \NAC"
BN"9"91;
%"TAP"
"6","(-3700,4725)","2","standard","I172";
;
CDS_LIB"standard"
BOM_COST"IO_SLOT"
BODY_TYPE"PLUMBING"
HDL_TAP"TRUE"
ROOM"RISER1";
"B \NAC \NWC"6;
"S \NAC"
BN"11"87;
%"TAP"
"6","(-3850,4875)","2","standard","I173";
;
CDS_LIB"standard"
BOM_COST"IO_SLOT"
BODY_TYPE"PLUMBING"
HDL_TAP"TRUE"
ROOM"RISER1";
"B \NAC \NWC"5;
"S \NAC"
BN"10"90;
%"TAP"
"6","(-3850,4775)","2","standard","I174";
;
CDS_LIB"standard"
BOM_COST"IO_SLOT"
BODY_TYPE"PLUMBING"
HDL_TAP"TRUE"
ROOM"RISER1";
"B \NAC \NWC"5;
"S \NAC"
BN"11"88;
%"TAP"
"6","(-3700,4625)","2","standard","I175";
;
CDS_LIB"standard"
BOM_COST"IO_SLOT"
BODY_TYPE"PLUMBING"
HDL_TAP"TRUE"
ROOM"RISER1";
"B \NAC \NWC"6;
"S \NAC"
BN"12"85;
%"TAP"
"6","(-3700,4525)","2","standard","I176";
;
CDS_LIB"standard"
BOM_COST"IO_SLOT"
BODY_TYPE"PLUMBING"
HDL_TAP"TRUE"
ROOM"RISER1";
"B \NAC \NWC"6;
"S \NAC"
BN"13"83;
%"TAP"
"6","(-3850,4575)","2","standard","I177";
;
CDS_LIB"standard"
BOM_COST"IO_SLOT"
BODY_TYPE"PLUMBING"
HDL_TAP"TRUE"
ROOM"RISER1";
"B \NAC \NWC"5;
"S \NAC"
BN"13"84;
%"TAP"
"6","(-3850,4675)","2","standard","I178";
;
CDS_LIB"standard"
BOM_COST"IO_SLOT"
BODY_TYPE"PLUMBING"
HDL_TAP"TRUE"
ROOM"RISER1";
"B \NAC \NWC"5;
"S \NAC"
BN"12"86;
%"TAP"
"6","(-3850,4475)","2","standard","I179";
;
CDS_LIB"standard"
BOM_COST"IO_SLOT"
BODY_TYPE"PLUMBING"
HDL_TAP"TRUE"
ROOM"RISER1";
"B \NAC \NWC"5;
"S \NAC"
BN"14"82;
%"TAP"
"6","(-3700,4325)","2","standard","I180";
;
CDS_LIB"standard"
BOM_COST"IO_SLOT"
BODY_TYPE"PLUMBING"
HDL_TAP"TRUE"
ROOM"RISER1";
"B \NAC \NWC"6;
"S \NAC"
BN"15"79;
%"TAP"
"6","(-3700,4425)","2","standard","I181";
;
BOM_COST"IO_SLOT"
CDS_LIB"standard"
BODY_TYPE"PLUMBING"
HDL_TAP"TRUE"
ROOM"RISER1";
"B \NAC \NWC"6;
"S \NAC"
BN"14"81;
%"TAP"
"6","(-3850,4375)","2","standard","I182";
;
CDS_LIB"standard"
BOM_COST"IO_SLOT"
BODY_TYPE"PLUMBING"
HDL_TAP"TRUE"
ROOM"RISER1";
"B \NAC \NWC"5;
"S \NAC"
BN"15"80;
%"TAP"
"6","(-3850,2350)","2","standard","I285";
;
BOM_COST"IO_SLOT"
CDS_LIB"standard"
BODY_TYPE"PLUMBING"
HDL_TAP"TRUE"
ROOM"RISER1";
"B \NAC \NWC"1;
"S \NAC"
BN"7"104;
%"TAP"
"6","(-3850,2450)","2","standard","I286";
;
BOM_COST"IO_SLOT"
CDS_LIB"standard"
BODY_TYPE"PLUMBING"
HDL_TAP"TRUE"
ROOM"RISER1";
"B \NAC \NWC"1;
"S \NAC"
BN"6"106;
%"TAP"
"6","(-3850,2650)","2","standard","I287";
;
BOM_COST"IO_SLOT"
CDS_LIB"standard"
BODY_TYPE"PLUMBING"
HDL_TAP"TRUE"
ROOM"RISER1";
"B \NAC \NWC"1;
"S \NAC"
BN"4"110;
%"TAP"
"6","(-3850,2550)","2","standard","I288";
;
BOM_COST"IO_SLOT"
CDS_LIB"standard"
BODY_TYPE"PLUMBING"
HDL_TAP"TRUE"
ROOM"RISER1";
"B \NAC \NWC"1;
"S \NAC"
BN"5"108;
%"TAP"
"6","(-6275,2350)","0","standard","I299";
;
CDS_LIB"standard"
BODY_TYPE"PLUMBING"
HDL_TAP"TRUE";
"B \NAC \NWC"9;
"S \NAC"
BN"7"22;
%"TAP"
"6","(-6275,2450)","0","standard","I300";
;
CDS_LIB"standard"
BODY_TYPE"PLUMBING"
HDL_TAP"TRUE";
"B \NAC \NWC"9;
"S \NAC"
BN"6"24;
%"TAP"
"6","(-6275,2650)","0","standard","I301";
;
CDS_LIB"standard"
BODY_TYPE"PLUMBING"
HDL_TAP"TRUE";
"B \NAC \NWC"9;
"S \NAC"
BN"4"28;
%"TAP"
"6","(-6275,2550)","0","standard","I302";
;
CDS_LIB"standard"
BODY_TYPE"PLUMBING"
HDL_TAP"TRUE";
"B \NAC \NWC"9;
"S \NAC"
BN"5"26;
%"TAP"
"6","(-3700,2600)","2","standard","I316";
;
BOM_COST"IO_SLOT"
CDS_LIB"standard"
BODY_TYPE"PLUMBING"
HDL_TAP"TRUE"
ROOM"RISER1";
"B \NAC \NWC"2;
"S \NAC"
BN"4"109;
%"TAP"
"6","(-3700,2500)","2","standard","I317";
;
BOM_COST"IO_SLOT"
CDS_LIB"standard"
BODY_TYPE"PLUMBING"
HDL_TAP"TRUE"
ROOM"RISER1";
"B \NAC \NWC"2;
"S \NAC"
BN"5"107;
%"TAP"
"6","(-3700,2400)","2","standard","I318";
;
BOM_COST"IO_SLOT"
CDS_LIB"standard"
BODY_TYPE"PLUMBING"
HDL_TAP"TRUE"
ROOM"RISER1";
"B \NAC \NWC"2;
"S \NAC"
BN"6"105;
%"TAP"
"6","(-3700,2300)","2","standard","I319";
;
BOM_COST"IO_SLOT"
CDS_LIB"standard"
BODY_TYPE"PLUMBING"
HDL_TAP"TRUE"
ROOM"RISER1";
"B \NAC \NWC"2;
"S \NAC"
BN"7"103;
%"TAP"
"6","(-6425,2600)","0","standard","I320";
;
CDS_LIB"standard"
BODY_TYPE"PLUMBING"
HDL_TAP"TRUE";
"B \NAC \NWC"10;
"S \NAC"
BN"4"27;
%"TAP"
"6","(-6425,2400)","0","standard","I321";
;
CDS_LIB"standard"
BODY_TYPE"PLUMBING"
HDL_TAP"TRUE";
"B \NAC \NWC"10;
"S \NAC"
BN"6"23;
%"TAP"
"6","(-6425,2500)","0","standard","I322";
;
CDS_LIB"standard"
BODY_TYPE"PLUMBING"
HDL_TAP"TRUE";
"B \NAC \NWC"10;
"S \NAC"
BN"5"25;
%"TAP"
"6","(-6425,2300)","0","standard","I323";
;
CDS_LIB"standard"
BODY_TYPE"PLUMBING"
HDL_TAP"TRUE";
"B \NAC \NWC"10;
"S \NAC"
BN"7"21;
%"TAP"
"6","(-6300,5875)","0","mstr_standard","I325";
;
CDS_LIB"mstr_standard"
BODY_TYPE"PLUMBING"
HDL_TAP"TRUE";
"B \NAC \NWC"7;
"S \NAC"
BN"0"46;
%"TAP"
"6","(-6300,5675)","0","mstr_standard","I326";
;
CDS_LIB"mstr_standard"
BODY_TYPE"PLUMBING"
HDL_TAP"TRUE";
"B \NAC \NWC"7;
"S \NAC"
BN"2"44;
%"TAP"
"6","(-6300,5775)","0","mstr_standard","I327";
;
CDS_LIB"mstr_standard"
BODY_TYPE"PLUMBING"
HDL_TAP"TRUE";
"B \NAC \NWC"7;
"S \NAC"
BN"1"45;
%"TAP"
"6","(-6450,5825)","0","mstr_standard","I328";
;
CDS_LIB"mstr_standard"
BODY_TYPE"PLUMBING"
HDL_TAP"TRUE";
"B \NAC \NWC"8;
"S \NAC"
BN"0"43;
%"TAP"
"6","(-6450,5725)","0","mstr_standard","I329";
;
CDS_LIB"mstr_standard"
BODY_TYPE"PLUMBING"
HDL_TAP"TRUE";
"B \NAC \NWC"8;
"S \NAC"
BN"1"41;
%"TAP"
"6","(-6300,5575)","0","standard","I330";
;
CDS_LIB"standard"
BODY_TYPE"PLUMBING"
HDL_TAP"TRUE";
"B \NAC \NWC"7;
"S \NAC"
BN"3"42;
%"TAP"
"6","(-6300,5475)","0","standard","I331";
;
CDS_LIB"standard"
BODY_TYPE"PLUMBING"
HDL_TAP"TRUE";
"B \NAC \NWC"7;
"S \NAC"
BN"4"40;
%"TAP"
"6","(-6300,5275)","0","standard","I332";
;
CDS_LIB"standard"
BODY_TYPE"PLUMBING"
HDL_TAP"TRUE";
"B \NAC \NWC"7;
"S \NAC"
BN"6"36;
%"TAP"
"6","(-6300,5375)","0","standard","I333";
;
CDS_LIB"standard"
BODY_TYPE"PLUMBING"
HDL_TAP"TRUE";
"B \NAC \NWC"7;
"S \NAC"
BN"5"38;
%"TAP"
"6","(-6300,5175)","0","standard","I334";
;
CDS_LIB"standard"
BODY_TYPE"PLUMBING"
HDL_TAP"TRUE";
"B \NAC \NWC"7;
"S \NAC"
BN"7"34;
%"TAP"
"6","(-6450,5525)","0","standard","I335";
;
CDS_LIB"standard"
BODY_TYPE"PLUMBING"
HDL_TAP"TRUE";
"B \NAC \NWC"8;
"S \NAC"
BN"3"37;
%"TAP"
"6","(-6450,5425)","0","standard","I336";
;
CDS_LIB"standard"
BODY_TYPE"PLUMBING"
HDL_TAP"TRUE";
"B \NAC \NWC"8;
"S \NAC"
BN"4"35;
%"TAP"
"6","(-6450,5625)","0","standard","I337";
;
CDS_LIB"standard"
BODY_TYPE"PLUMBING"
HDL_TAP"TRUE";
"B \NAC \NWC"8;
"S \NAC"
BN"2"39;
%"TAP"
"6","(-6450,5325)","0","standard","I338";
;
CDS_LIB"standard"
BODY_TYPE"PLUMBING"
HDL_TAP"TRUE";
"B \NAC \NWC"8;
"S \NAC"
BN"5"33;
%"TAP"
"6","(-6450,5225)","0","standard","I339";
;
CDS_LIB"standard"
BODY_TYPE"PLUMBING"
HDL_TAP"TRUE";
"B \NAC \NWC"8;
"S \NAC"
BN"6"32;
%"TAP"
"6","(-6300,5075)","0","standard","I340";
;
CDS_LIB"standard"
BODY_TYPE"PLUMBING"
HDL_TAP"TRUE";
"B \NAC \NWC"7;
"S \NAC"
BN"8"62;
%"TAP"
"6","(-6300,4975)","0","standard","I341";
;
CDS_LIB"standard"
BODY_TYPE"PLUMBING"
HDL_TAP"TRUE";
"B \NAC \NWC"7;
"S \NAC"
BN"9"60;
%"TAP"
"6","(-6300,4875)","0","standard","I342";
;
CDS_LIB"standard"
BODY_TYPE"PLUMBING"
HDL_TAP"TRUE";
"B \NAC \NWC"7;
"S \NAC"
BN"10"58;
%"TAP"
"6","(-6300,4775)","0","standard","I343";
;
CDS_LIB"standard"
BODY_TYPE"PLUMBING"
HDL_TAP"TRUE";
"B \NAC \NWC"7;
"S \NAC"
BN"11"56;
%"TAP"
"6","(-6300,4675)","0","standard","I344";
;
CDS_LIB"standard"
BODY_TYPE"PLUMBING"
HDL_TAP"TRUE";
"B \NAC \NWC"7;
"S \NAC"
BN"12"54;
%"TAP"
"6","(-6450,5125)","0","standard","I345";
;
CDS_LIB"standard"
BODY_TYPE"PLUMBING"
HDL_TAP"TRUE";
"B \NAC \NWC"8;
"S \NAC"
BN"7"31;
%"TAP"
"6","(-6450,4925)","0","standard","I346";
;
CDS_LIB"standard"
BODY_TYPE"PLUMBING"
HDL_TAP"TRUE";
"B \NAC \NWC"8;
"S \NAC"
BN"9"59;
%"TAP"
"6","(-6450,5025)","0","standard","I347";
;
CDS_LIB"standard"
BODY_TYPE"PLUMBING"
HDL_TAP"TRUE";
"B \NAC \NWC"8;
"S \NAC"
BN"8"61;
%"TAP"
"6","(-6450,4825)","0","standard","I348";
;
CDS_LIB"standard"
BODY_TYPE"PLUMBING"
HDL_TAP"TRUE";
"B \NAC \NWC"8;
"S \NAC"
BN"10"57;
%"TAP"
"6","(-6450,4725)","0","standard","I349";
;
CDS_LIB"standard"
BODY_TYPE"PLUMBING"
HDL_TAP"TRUE";
"B \NAC \NWC"8;
"S \NAC"
BN"11"55;
%"TAP"
"6","(-6300,4575)","0","standard","I350";
;
CDS_LIB"standard"
BODY_TYPE"PLUMBING"
HDL_TAP"TRUE";
"B \NAC \NWC"7;
"S \NAC"
BN"13"52;
%"TAP"
"6","(-6300,4475)","0","standard","I351";
;
CDS_LIB"standard"
BODY_TYPE"PLUMBING"
HDL_TAP"TRUE";
"B \NAC \NWC"7;
"S \NAC"
BN"14"50;
%"TAP"
"6","(-6300,4375)","0","standard","I352";
;
CDS_LIB"standard"
BODY_TYPE"PLUMBING"
HDL_TAP"TRUE";
"B \NAC \NWC"7;
"S \NAC"
BN"15"48;
%"TAP"
"6","(-6450,4625)","0","standard","I353";
;
CDS_LIB"standard"
BODY_TYPE"PLUMBING"
HDL_TAP"TRUE";
"B \NAC \NWC"8;
"S \NAC"
BN"12"53;
%"TAP"
"6","(-6450,4425)","0","standard","I354";
;
CDS_LIB"standard"
BODY_TYPE"PLUMBING"
HDL_TAP"TRUE";
"B \NAC \NWC"8;
"S \NAC"
BN"14"49;
%"TAP"
"6","(-6450,4525)","0","standard","I355";
;
CDS_LIB"standard"
BODY_TYPE"PLUMBING"
HDL_TAP"TRUE";
"B \NAC \NWC"8;
"S \NAC"
BN"13"51;
%"TAP"
"6","(-6450,4325)","0","standard","I356";
;
CDS_LIB"standard"
BODY_TYPE"PLUMBING"
HDL_TAP"TRUE";
"B \NAC \NWC"8;
"S \NAC"
BN"15"47;
%"TAP"
"6","(-3850,2250)","2","standard","I382";
;
CDS_LIB"standard"
BOM_COST"IO_SLOT"
BODY_TYPE"PLUMBING"
HDL_TAP"TRUE"
ROOM"RISER1";
"B \NAC \NWC"3;
"S \NAC"
BN"8"102;
%"TAP"
"6","(-3850,2150)","2","standard","I383";
;
CDS_LIB"standard"
BOM_COST"IO_SLOT"
BODY_TYPE"PLUMBING"
HDL_TAP"TRUE"
ROOM"RISER1";
"B \NAC \NWC"3;
"S \NAC"
BN"9"100;
%"TAP"
"6","(-3850,1950)","2","standard","I387";
;
CDS_LIB"standard"
BOM_COST"IO_SLOT"
BODY_TYPE"PLUMBING"
HDL_TAP"TRUE"
ROOM"RISER1";
"B \NAC \NWC"3;
"S \NAC"
BN"11"96;
%"TAP"
"6","(-3850,2050)","2","standard","I388";
;
CDS_LIB"standard"
BOM_COST"IO_SLOT"
BODY_TYPE"PLUMBING"
HDL_TAP"TRUE"
ROOM"RISER1";
"B \NAC \NWC"3;
"S \NAC"
BN"10"98;
%"TAP"
"6","(-6275,2150)","0","standard","I389";
;
CDS_LIB"standard"
BODY_TYPE"PLUMBING"
HDL_TAP"TRUE";
"B \NAC \NWC"11;
"S \NAC"
BN"9"18;
%"TAP"
"6","(-6275,2250)","0","standard","I390";
;
CDS_LIB"standard"
BODY_TYPE"PLUMBING"
HDL_TAP"TRUE";
"B \NAC \NWC"11;
"S \NAC"
BN"8"20;
%"TAP"
"6","(-6275,2050)","0","standard","I392";
;
CDS_LIB"standard"
BODY_TYPE"PLUMBING"
HDL_TAP"TRUE";
"B \NAC \NWC"11;
"S \NAC"
BN"10"16;
%"TAP"
"6","(-6275,1950)","0","standard","I393";
;
CDS_LIB"standard"
BODY_TYPE"PLUMBING"
HDL_TAP"TRUE";
"B \NAC \NWC"11;
"S \NAC"
BN"11"14;
%"TAP"
"6","(-6425,2200)","0","standard","I399";
;
CDS_LIB"standard"
BODY_TYPE"PLUMBING"
HDL_TAP"TRUE";
"B \NAC \NWC"12;
"S \NAC"
BN"8"19;
%"TAP"
"6","(-6425,2100)","0","standard","I400";
;
CDS_LIB"standard"
BODY_TYPE"PLUMBING"
HDL_TAP"TRUE";
"B \NAC \NWC"12;
"S \NAC"
BN"9"17;
%"TAP"
"6","(-6425,2000)","0","standard","I401";
;
CDS_LIB"standard"
BODY_TYPE"PLUMBING"
HDL_TAP"TRUE";
"B \NAC \NWC"12;
"S \NAC"
BN"10"15;
%"TAP"
"6","(-6425,1900)","0","standard","I402";
;
CDS_LIB"standard"
BODY_TYPE"PLUMBING"
HDL_TAP"TRUE";
"B \NAC \NWC"12;
"S \NAC"
BN"11"13;
%"TAP"
"6","(-3700,1900)","2","standard","I404";
;
CDS_LIB"standard"
BOM_COST"IO_SLOT"
BODY_TYPE"PLUMBING"
HDL_TAP"TRUE"
ROOM"RISER1";
"B \NAC \NWC"4;
"S \NAC"
BN"11"95;
%"TAP"
"6","(-3700,2200)","2","standard","I406";
;
CDS_LIB"standard"
BOM_COST"IO_SLOT"
BODY_TYPE"PLUMBING"
HDL_TAP"TRUE"
ROOM"RISER1";
"B \NAC \NWC"4;
"S \NAC"
BN"8"101;
%"TAP"
"6","(-3700,2100)","2","standard","I407";
;
CDS_LIB"standard"
BOM_COST"IO_SLOT"
BODY_TYPE"PLUMBING"
HDL_TAP"TRUE"
ROOM"RISER1";
"B \NAC \NWC"4;
"S \NAC"
BN"9"99;
%"TAP"
"6","(-3700,2000)","2","standard","I408";
;
CDS_LIB"standard"
BOM_COST"IO_SLOT"
BODY_TYPE"PLUMBING"
HDL_TAP"TRUE"
ROOM"RISER1";
"B \NAC \NWC"4;
"S \NAC"
BN"10"97;
END.
